# T6G (Grand Teton) — schematic netlist excerpt (pin names and nets, part order shuffled) for the footprints in the layout excerpt that follows; sources: Cadence DE-HDL packaged netlist, KiCad conversion of 04192023_DAF0TMB3IC0_F0TG_MB_C_brd_V02_OCP.brd

Q29  MOSFET_N_GSD  NX138BK IC  pkg SOT23_GDSXE  page 165
  DRAIN  = LED_BIOS_DBG_MODE
  GATE  = LED_BIOS_DBG_MODE_N
  SOURCE  = GND

PD108  SCHOTTKY_AC  B340A-13-F IC  pkg D2010XF  page 140 : A = GND ; C = P12V_OCP_V3_2
C106  Q_CAP  0.1UF 25V 10% X7R  pkg 0402  page 250 : A = P3V3_AUX ; B = GND

(kicad_pcb
	(version 20260206)
	(generator "pcbnew")
	(generator_version "10.0")
	(general
		(thickness 1.6)
		(legacy_teardrops no)
	)
	(paper "A4")
	(title_block
		(title "04192023_DAF0TMB3IC0_F0TG_MB_C_brd_V02_OCP.brd")
		(comment 1 "Grand Teton / footprints 660-662 of 8354")
	)
	(layers
		(0 "F.Cu" signal "TOP")
		(4 "In1.Cu" signal "GND")
		(6 "In2.Cu" signal "IN1")
		(8 "In3.Cu" signal "GND1")
		(10 "In4.Cu" signal "IN2")
		(12 "In5.Cu" signal "GND2")
		(14 "In6.Cu" signal "IN3")
		(16 "In7.Cu" signal "GND3")
		(18 "In8.Cu" signal "VCC")
		(20 "In9.Cu" signal "VCC1")
		(22 "In10.Cu" signal "GND4")
		(24 "In11.Cu" signal "IN4")
		(26 "In12.Cu" signal "GND5")
		(28 "In13.Cu" signal "IN5")
		(30 "In14.Cu" signal "GND6")
		(32 "In15.Cu" signal "IN6")
		(34 "In16.Cu" signal "GND7")
		(2 "B.Cu" signal "BOTTOM")
		(9 "F.Adhes" user "F.Adhesive")
		(11 "B.Adhes" user "B.Adhesive")
		(13 "F.Paste" user "Package Geometry/Pastemask Top")
		(15 "B.Paste" user "Package Geometry/Pastemask Bottom")
		(5 "F.SilkS" user "Ref Des/Silkscreen Top")
		(7 "B.SilkS" user "Ref Des/Silkscreen Bottom")
		(1 "F.Mask" user "Board Geometry/Soldermask Top")
		(3 "B.Mask" user "Board Geometry/Soldermask Bottom")
		(17 "Dwgs.User" user "User.Drawings")
		(19 "Cmts.User" user "User.Comments")
		(21 "Eco1.User" user "User.Eco1")
		(23 "Eco2.User" user "User.Eco2")
		(25 "Edge.Cuts" user "Board Geometry/Outline")
		(27 "Margin" user)
		(31 "F.CrtYd" user "Package Geometry/Place Bound Top")
		(29 "B.CrtYd" user "Package Geometry/Place Bound Bottom")
		(35 "F.Fab" user "Ref Des/Assembly Top")
		(33 "B.Fab" user "Ref Des/Assembly Bottom")
	)
	(footprint ""
		(layer "F.Cu")
		(at 81.424018 -15.177262 180)
		(property "Reference" "PD108"
			(at -5.42798 0.894588 0)
			(unlocked yes)
			(layer "F.SilkS")
			(effects
				(font
					(size 0.7874 0.5842)
					(thickness 0.1524)
				)
				(justify left)
			)
		)
		(property "Value" ""
			(at 0 0 180)
			(layer "F.Fab")
			(effects
				(font
					(size 1.27 1.27)
				)
			)
		)
		(duplicate_pad_numbers_are_jumpers no)
		(fp_line
			(start 4.107942 1.459992)
			(end -3.400044 1.459992)
			(stroke
				(width 0.1524)
				(type default)
			)
			(layer "F.SilkS")
		)
		(fp_line
			(start 4.107942 -1.459992)
			(end 4.107942 1.459992)
			(stroke
				(width 0.1524)
				(type default)
			)
			(layer "F.SilkS")
		)
		(fp_line
			(start -3.400044 1.459992)
			(end -3.400044 -1.459992)
			(stroke
				(width 0.1524)
				(type default)
			)
			(layer "F.SilkS")
		)
		(fp_line
			(start -3.400044 -1.459992)
			(end 4.107942 -1.459992)
			(stroke
				(width 0.1524)
				(type default)
			)
			(layer "F.SilkS")
		)
		(fp_rect
			(start 4.107942 -1.459992)
			(end 3.308096 1.459992)
			(stroke
				(width 0)
				(type default)
			)
			(fill yes)
			(layer "F.SilkS")
		)
		(fp_line
			(start 2.29997 1.459992)
			(end -2.29997 1.459992)
			(stroke
				(width 0.1)
				(type default)
			)
			(layer "F.Fab")
		)
		(fp_line
			(start 2.29997 -1.459992)
			(end 2.29997 1.459992)
			(stroke
				(width 0.1)
				(type default)
			)
			(layer "F.Fab")
		)
		(fp_line
			(start -2.29997 1.459992)
			(end -2.29997 -1.459992)
			(stroke
				(width 0.1)
				(type default)
			)
			(layer "F.Fab")
		)
		(fp_line
			(start -2.29997 -1.459992)
			(end 2.29997 -1.459992)
			(stroke
				(width 0.1)
				(type default)
			)
			(layer "F.Fab")
		)
		(fp_text user "-"
			(at 5.4102 0.29845 0)
			(unlocked yes)
			(layer "F.SilkS")
			(effects
				(font
					(size 1.905 1.4224)
					(thickness 0.1524)
				)
				(justify left)
			)
		)
		(fp_text user "+"
			(at -4.7752 -0.12065 180)
			(unlocked yes)
			(layer "F.SilkS")
			(effects
				(font
					(size 1.905 1.4224)
					(thickness 0.1524)
				)
				(justify left)
			)
		)
		(fp_text user "-"
			(at 5.4102 0.29845 0)
			(unlocked yes)
			(layer "F.Fab")
			(effects
				(font
					(size 1.905 1.4224)
					(thickness 0.1524)
				)
				(justify left)
			)
		)
		(fp_text user "+"
			(at -4.7752 -0.12065 180)
			(unlocked yes)
			(layer "F.Fab")
			(effects
				(font
					(size 1.905 1.4224)
					(thickness 0.1524)
				)
				(justify left)
			)
		)
		(pad "A" smd rect
			(at -1.999996 0 270)
			(size 1.7018 2.5146)
			(layers "F.Cu" "F.Mask" "F.Paste")
			(net "GND")
		)
		(pad "C" smd rect
			(at 1.999996 0 270)
			(size 1.7018 2.5146)
			(layers "F.Cu" "F.Mask" "F.Paste")
			(net "P12V_OCP_V3_2")
		)
	)
	(footprint ""
		(layer "F.Cu")
		(at 336.195416 -20.136612 -90)
		(property "Reference" "Q29"
			(at -0.557276 2.35966 90)
			(unlocked yes)
			(layer "F.SilkS")
			(effects
				(font
					(size 0.7874 0.5842)
					(thickness 0.1524)
				)
			)
		)
		(property "Value" ""
			(at 0 0 270)
			(layer "F.Fab")
			(effects
				(font
					(size 1.27 1.27)
				)
			)
		)
		(duplicate_pad_numbers_are_jumpers no)
		(fp_line
			(start -1.8796 1.651)
			(end -1.8796 -1.651)
			(stroke
				(width 0.1524)
				(type default)
			)
			(layer "F.SilkS")
		)
		(fp_line
			(start 1.8796 1.651)
			(end -1.8796 1.651)
			(stroke
				(width 0.1524)
				(type default)
			)
			(layer "F.SilkS")
		)
		(fp_line
			(start -1.8796 -1.651)
			(end 1.8796 -1.651)
			(stroke
				(width 0.1524)
				(type default)
			)
			(layer "F.SilkS")
		)
		(fp_line
			(start 1.8796 -1.651)
			(end 1.8796 1.651)
			(stroke
				(width 0.1524)
				(type default)
			)
			(layer "F.SilkS")
		)
		(fp_line
			(start -0.700024 1.500124)
			(end -0.700024 -1.500124)
			(stroke
				(width 0.1)
				(type default)
			)
			(layer "F.Fab")
		)
		(fp_line
			(start 0.700024 1.500124)
			(end -0.700024 1.500124)
			(stroke
				(width 0.1)
				(type default)
			)
			(layer "F.Fab")
		)
		(fp_line
			(start -0.700024 -1.500124)
			(end 0.700024 -1.500124)
			(stroke
				(width 0.1)
				(type default)
			)
			(layer "F.Fab")
		)
		(fp_line
			(start 0.700024 -1.500124)
			(end 0.700024 1.500124)
			(stroke
				(width 0.1)
				(type default)
			)
			(layer "F.Fab")
		)
		(pad "D" smd rect
			(at 1.119886 0 180)
			(size 1.016 1.2192)
			(layers "F.Cu" "F.Mask" "F.Paste")
			(net "LED_BIOS_DBG_MODE")
		)
		(pad "G" smd rect
			(at -1.119886 -0.999998 180)
			(size 1.016 1.2192)
			(layers "F.Cu" "F.Mask" "F.Paste")
			(net "LED_BIOS_DBG_MODE_N")
		)
		(pad "S" smd rect
			(at -1.119886 0.999998 180)
			(size 1.016 1.2192)
			(layers "F.Cu" "F.Mask" "F.Paste")
			(net "GND")
		)
	)
	(footprint ""
		(layer "F.Cu")
		(at 291.144452 -124.414026)
		(property "Reference" "C106"
			(at 0 0 0)
			(layer "F.SilkS")
			(hide yes)
			(effects
				(font
					(size 1.27 1.27)
				)
			)
		)
		(property "Value" ""
			(at 0 0 0)
			(layer "F.Fab")
			(effects
				(font
					(size 1.27 1.27)
				)
			)
		)
		(duplicate_pad_numbers_are_jumpers no)
		(fp_line
			(start -0.7874 -0.4064)
			(end 0.7874 -0.4064)
			(stroke
				(width 0.1524)
				(type default)
			)
			(layer "F.SilkS")
		)
		(fp_line
			(start -0.7874 0.4064)
			(end -0.7874 -0.4064)
			(stroke
				(width 0.1524)
				(type default)
			)
			(layer "F.SilkS")
		)
		(fp_line
			(start 0.7874 -0.4064)
			(end 0.7874 0.4064)
			(stroke
				(width 0.1524)
				(type default)
			)
			(layer "F.SilkS")
		)
		(fp_line
			(start 0.7874 0.4064)
			(end -0.7874 0.4064)
			(stroke
				(width 0.1524)
				(type default)
			)
			(layer "F.SilkS")
		)
		(fp_line
			(start -0.67945 -0.305054)
			(end -0.12065 -0.305054)
			(stroke
				(width 0.1)
				(type default)
			)
			(layer "F.Fab")
		)
		(fp_line
			(start -0.67945 0.3048)
			(end -0.67945 -0.305054)
			(stroke
				(width 0.1)
				(type default)
			)
			(layer "F.Fab")
		)
		(fp_line
			(start -0.12065 -0.305054)
			(end -0.12065 -0.2794)
			(stroke
				(width 0.1)
				(type default)
			)
			(layer "F.Fab")
		)
		(fp_line
			(start -0.12065 -0.2794)
			(end 0.12065 -0.2794)
			(stroke
				(width 0.1)
				(type default)
			)
			(layer "F.Fab")
		)
		(fp_line
			(start -0.12065 0.2794)
			(end -0.12065 0.3048)
			(stroke
				(width 0.1)
				(type default)
			)
			(layer "F.Fab")
		)
		(fp_line
			(start -0.12065 0.3048)
			(end -0.67945 0.3048)
			(stroke
				(width 0.1)
				(type default)
			)
			(layer "F.Fab")
		)
		(fp_line
			(start 0.120396 0.2794)
			(end -0.12065 0.2794)
			(stroke
				(width 0.1)
				(type default)
			)
			(layer "F.Fab")
		)
		(fp_line
			(start 0.120396 0.3048)
			(end 0.120396 0.2794)
			(stroke
				(width 0.1)
				(type default)
			)
			(layer "F.Fab")
		)
		(fp_line
			(start 0.12065 -0.3048)
			(end 0.67945 -0.3048)
			(stroke
				(width 0.1)
				(type default)
			)
			(layer "F.Fab")
		)
		(fp_line
			(start 0.12065 -0.2794)
			(end 0.12065 -0.3048)
			(stroke
				(width 0.1)
				(type default)
			)
			(layer "F.Fab")
		)
		(fp_line
			(start 0.67945 -0.3048)
			(end 0.67945 0.3048)
			(stroke
				(width 0.1)
				(type default)
			)
			(layer "F.Fab")
		)
		(fp_line
			(start 0.67945 0.3048)
			(end 0.120396 0.3048)
			(stroke
				(width 0.1)
				(type default)
			)
			(layer "F.Fab")
		)
		(pad "1" smd circle
			(at -0.40005 0)
			(size 0 0)
			(layers "F.Cu" "F.Mask" "F.Paste")
			(net "P3V3_AUX")
		)
		(pad "2" smd circle
			(at 0.40005 0)
			(size 0 0)
			(layers "F.Cu" "F.Mask" "F.Paste")
			(net "GND")
		)
	)
)
